# S9S_MB_2U (Grand Teton) — schematic netlist excerpt (pin names and nets, part order shuffled) for the footprints in the layout excerpt that follows; sources: Cadence DE-HDL packaged netlist, KiCad conversion of 03242023_DA0F0TMBIJ0_F0T_Motherboard_J_brd_V01_OCP.brd

J14  SCONN288_ADR50017P087CC  SCONN288_ADR50017-P087CC IO  pkg DDR288S_1-1VXB  page 95
  VIN_BULK0  = P12V_S3_AUX_CPU0_NVDIMM
  RFU0  = TP_CHG_CPU0_DIMM2_FRU_0
  VIN_MGMT  = P3V3_AUX
  HSCL  = I3C_SPD_DDREFGH_CPU0_LVC1_SCL_5
  HSDA  = I3C_SPD_DDREFGH_CPU0_LVC1_SDA
  VSS0  = GND
  DQ0_A  = M_G_CPU0_SA_DQ<0>
  VSS1  = GND
  DQ1_A  = M_G_CPU0_SA_DQ<1>
  VSS2  = GND
  DQS0_A_T  = M_G_CPU0_SA_DQS_DP<0>
  DQS0_A_C  = M_G_CPU0_SA_DQS_DN<0>
  VSS3  = GND
  DQ4_A  = M_G_CPU0_SA_DQ<4>
  VSS4  = GND
  DQ5_A  = M_G_CPU0_SA_DQ<5>
  VSS5  = GND
  DQ8_A  = M_G_CPU0_SA_DQ<8>
  VSS6  = GND
  DQ9_A  = M_G_CPU0_SA_DQ<9>
  VSS7  = GND
  DQS1_A_T  = M_G_CPU0_SA_DQS_DP<1>
  DQS1_A_C  = M_G_CPU0_SA_DQS_DN<1>
  VSS8  = GND
  DQ12_A  = M_G_CPU0_SA_DQ<12>
  VSS9  = GND
  DQ13_A  = M_G_CPU0_SA_DQ<13>
  VSS10  = GND
  DQ16_A  = M_G_CPU0_SA_DQ<16>
  VSS11  = GND
  DQ17_A  = M_G_CPU0_SA_DQ<17>
  VSS12  = GND
  DQS2_A_T  = M_G_CPU0_SA_DQS_DP<2>
  DQS2_A_C  = M_G_CPU0_SA_DQS_DN<2>
  VSS13  = GND
  DQ20_A  = M_G_CPU0_SA_DQ<20>
  VSS14  = GND
  DQ21_A  = M_G_CPU0_SA_DQ<21>
  VSS15  = GND
  DQ24_A  = M_G_CPU0_SA_DQ<24>
  VSS16  = GND
  DQ25_A  = M_G_CPU0_SA_DQ<25>
  VSS17  = GND
  DQS3_A_T  = M_G_CPU0_SA_DQS_DP<3>
  DQS3_A_C  = M_G_CPU0_SA_DQS_DN<3>
  VSS18  = GND
  DQ28_A  = M_G_CPU0_SA_DQ<28>
  VSS19  = GND
  DQ29_A  = M_G_CPU0_SA_DQ<29>
  VSS20  = GND
  CB0_A  = M_G_CPU0_SA_CB<0>
  VSS21  = GND
  CB1_A  = M_G_CPU0_SA_CB<1>
  VSS22  = GND
  DQS4_A_T  = M_G_CPU0_SA_DQS_DP<4>
  DQS4_A_C  = M_G_CPU0_SA_DQS_DN<4>
  VSS23  = GND
  CB4_A  = M_G_CPU0_SA_CB<4>
  VSS24  = GND
  CB5_A  = M_G_CPU0_SA_CB<5>
  VSS25  = GND
  ALERT_N  = M_G_CPU0_ALERT_N
  VSS26  = GND
  CS0_A_N  = M_G_CPU0_SA_CS_N<2>
  VSS27  = GND
  CA0_A  = M_G_CPU0_SA_CA<0>
  VSS28  = GND
  CA2_A  = M_G_CPU0_SA_CA<2>
  VSS29  = GND
  CA4_A  = M_G_CPU0_SA_CA<4>
  VSS30  = GND
  CA6_A  = M_G_CPU0_SA_CA<6>
  VSS31  = GND
  PAR_A  = M_G_CPU0_SA_PAR
  VSS32  = GND
  CA0_B  = M_G_CPU0_SB_CA<0>
  VSS33  = GND
  CA2_B  = M_G_CPU0_SB_CA<2>
  VSS34  = GND
  CA4_B  = M_G_CPU0_SB_CA<4>
  VSS35  = GND
  CA6_B  = M_G_CPU0_SB_CA<6>
  VSS36  = GND
  CS0_B_N  = M_G_CPU0_SB_CS_N<2>
  VSS37  = GND
  \lbd||rsp_a_n\  = M_G_CPU0_SA_RSP<1>
  \lbs||rsp_b_n\  = M_G_CPU0_SB_RSP<1>
  VSS38  = GND
  CB4_B  = M_G_CPU0_SB_CB<4>
  VSS39  = GND
  CB5_B  = M_G_CPU0_SB_CB<5>
  VSS40  = GND
  \dqs9_b_t||tdqs9_b_t||dbi4_b_n\  = M_G_CPU0_SB_DQS_DP<9>
  \dqs9_b_c||tdqs9_b_c\  = M_G_CPU0_SB_DQS_DN<9>
  VSS41  = GND
  CB0_B  = M_G_CPU0_SB_CB<0>
  VSS42  = GND
  CB1_B  = M_G_CPU0_SB_CB<1>
  VSS43  = GND
  DQ0_B  = M_G_CPU0_SB_DQ<0>
  VSS44  = GND
  DQ1_B  = M_G_CPU0_SB_DQ<1>
  VSS45  = GND
  DQS0_B_T  = M_G_CPU0_SB_DQS_DP<0>
  DQS0_B_C  = M_G_CPU0_SB_DQS_DN<0>
  VSS46  = GND
  DQ4_B  = M_G_CPU0_SB_DQ<4>
  VSS47  = GND
  DQ5_B  = M_G_CPU0_SB_DQ<5>
  VSS48  = GND
  DQ8_B  = M_G_CPU0_SB_DQ<8>
  VSS49  = GND
  DQ9_B  = M_G_CPU0_SB_DQ<9>
  VSS50  = GND
  DQS1_B_T  = M_G_CPU0_SB_DQS_DP<1>
  DQS1_B_C  = M_G_CPU0_SB_DQS_DN<1>
  VSS51  = GND
  DQ12_B  = M_G_CPU0_SB_DQ<12>
  VSS52  = GND
  DQ13_B  = M_G_CPU0_SB_DQ<13>
  VSS53  = GND
  DQ16_B  = M_G_CPU0_SB_DQ<16>
  VSS54  = GND
  DQ17_B  = M_G_CPU0_SB_DQ<17>
  VSS55  = GND
  DQS2_B_T  = M_G_CPU0_SB_DQS_DP<2>
  DQS2_B_C  = M_G_CPU0_SB_DQS_DN<2>
  VSS56  = GND
  DQ20_B  = M_G_CPU0_SB_DQ<20>
  VSS57  = GND
  DQ21_B  = M_G_CPU0_SB_DQ<21>
  VSS58  = GND
  DQ24_B  = M_G_CPU0_SB_DQ<24>
  VSS59  = GND
  DQ25_B  = M_G_CPU0_SB_DQ<25>
  VSS60  = GND
  DQS3_B_T  = M_G_CPU0_SB_DQS_DP<3>
  DQS3_B_C  = M_G_CPU0_SB_DQS_DN<3>
  VSS61  = GND
  DQ28_B  = M_G_CPU0_SB_DQ<28>
  VSS62  = GND
  DQ29_B  = M_G_CPU0_SB_DQ<29>
  VSS63  = GND
  RFU1  = TP_CHG_CPU0_DIMM2_FRU_1
  VIN_BULK1  = P12V_S3_AUX_CPU0_NVDIMM
  VIN_BULK2  = P12V_S3_AUX_CPU0_NVDIMM
  \pwr_good||fail_n\  = PWRGD_CHG_CPU0_DIMM2
  HSA  = PD_CHG_CPU0_DIMM2_SAA
  RFU2  = TP_CHG_CPU0_DIMM2_FRU_2
  RFU3  = TP_CHG_CPU0_DIMM2_FRU_3
  VSS64  = GND
  DQ2_A  = M_G_CPU0_SA_DQ<2>
  VSS65  = GND
  DQ3_A  = M_G_CPU0_SA_DQ<3>
  VSS66  = GND
  \dqs5_a_c||tdqs5_a_c||dqs5_a_t||tdqs5_a_t\  = M_G_CPU0_SA_DQS_DN<5>
  \dqs5_a_t||tdqs5_a_t\  = M_G_CPU0_SA_DQS_DP<5>
  VSS67  = GND
  DQ6_A  = M_G_CPU0_SA_DQ<6>
  VSS68  = GND
  DQ7_A  = M_G_CPU0_SA_DQ<7>
  VSS69  = GND
  DQ10_A  = M_G_CPU0_SA_DQ<10>
  VSS70  = GND
  DQ11_A  = M_G_CPU0_SA_DQ<11>
  VSS71  = GND
  \dqs6_a_c||tdqs6_a_c||dqs6_a_t||tdqs6_a_t\  = M_G_CPU0_SA_DQS_DN<6>
  \dqs6_a_t||tdqs6_a_t\  = M_G_CPU0_SA_DQS_DP<6>
  VSS72  = GND
  DQ14_A  = M_G_CPU0_SA_DQ<14>
  VSS73  = GND
  DQ15_A  = M_G_CPU0_SA_DQ<15>
  VSS74  = GND
  DQ18_A  = M_G_CPU0_SA_DQ<18>
  VSS75  = GND
  DQ19_A  = M_G_CPU0_SA_DQ<19>
  VSS76  = GND
  \dqs7_a_c||tdqs7_a_c\  = M_G_CPU0_SA_DQS_DN<7>
  \dqs7_a_t||tdqs7_a_t\  = M_G_CPU0_SA_DQS_DP<7>
  VSS77  = GND
  DQ22_A  = M_G_CPU0_SA_DQ<22>
  VSS78  = GND
  DQ23_A  = M_G_CPU0_SA_DQ<23>
  VSS79  = GND
  DQ26_A  = M_G_CPU0_SA_DQ<26>
  VSS80  = GND
  DQ27_A  = M_G_CPU0_SA_DQ<27>
  VSS81  = GND
  \dqs8_a_c||tdqs8_a_c\  = M_G_CPU0_SA_DQS_DN<8>
  \dqs8_a_t||tdqs8_a_t\  = M_G_CPU0_SA_DQS_DP<8>
  VSS82  = GND
  DQ30_A  = M_G_CPU0_SA_DQ<30>
  VSS83  = GND
  DQ31_A  = M_G_CPU0_SA_DQ<31>
  VSS84  = GND
  CB2_A  = M_G_CPU0_SA_CB<2>
  VSS85  = GND
  CB3_A  = M_G_CPU0_SA_CB<3>
  VSS86  = GND
  \dqs9_a_c||tdqs9_a_c\  = M_G_CPU0_SA_DQS_DN<9>
  \dqs9_a_t||tdqs9_a_t\  = M_G_CPU0_SA_DQS_DP<9>
  VSS87  = GND
  CB6_A  = M_G_CPU0_SA_CB<6>
  VSS88  = GND
  CB7_A  = M_G_CPU0_SA_CB<7>
  VSS89  = GND
  RESET_N  = RST_M_GH_CPU0_FPGA_N
  VSS90  = GND
  CS1_A_N  = M_G_CPU0_SA_CS_N<3>
  VSS91  = GND
  CA1_A  = M_G_CPU0_SA_CA<1>
  VSS92  = GND
  CA3_A  = M_G_CPU0_SA_CA<3>
  VSS93  = GND
  CA5_A  = M_G_CPU0_SA_CA<5>
  VSS94  = GND
  CK_T  = M_G_CPU0_CLK_DP<1>
  CK_C  = M_G_CPU0_CLK_DN<1>
  VSS95  = GND
  RFU4  = TP_CHG_CPU0_DIMM2_FRU_4
  CA1_B  = M_G_CPU0_SB_CA<1>
  VSS96  = GND
  CA3_B  = M_G_CPU0_SB_CA<3>
  VSS97  = GND
  CA5_B  = M_G_CPU0_SB_CA<5>
  VSS98  = GND
  PAR_B  = M_G_CPU0_SB_PAR
  VSS99  = GND
  CS1_B_N  = M_G_CPU0_SB_CS_N<3>
  VSS100  = GND
  RFU5  = TP_CHG_CPU0_DIMM2_FRU_5
  RFU6  = TP_CHG_CPU0_DIMM2_FRU_6
  VSS101  = GND
  CB6_B  = M_G_CPU0_SB_CB<6>
  VSS102  = GND
  CB7_B  = M_G_CPU0_SB_CB<7>
  VSS103  = GND
  DQS4_B_C  = M_G_CPU0_SB_DQS_DN<4>
  DQS4_B_T  = M_G_CPU0_SB_DQS_DP<4>
  VSS104  = GND
  CB2_B  = M_G_CPU0_SB_CB<2>
  VSS105  = GND
  CB3_B  = M_G_CPU0_SB_CB<3>
  VSS106  = GND
  DQ2_B  = M_G_CPU0_SB_DQ<2>
  VSS107  = GND
  DQ3_B  = M_G_CPU0_SB_DQ<3>
  VSS108  = GND
  \dqs5_b_c||tdqs5_b_c\  = M_G_CPU0_SB_DQS_DN<5>
  \dqs5_b_t||tdqs5_b_t\  = M_G_CPU0_SB_DQS_DP<5>
  VSS109  = GND
  DQ6_B  = M_G_CPU0_SB_DQ<6>
  VSS110  = GND
  DQ7_B  = M_G_CPU0_SB_DQ<7>
  VSS111  = GND
  DQ10_B  = M_G_CPU0_SB_DQ<10>
  VSS112  = GND
  DQ11_B  = M_G_CPU0_SB_DQ<11>
  VSS113  = GND
  \dqs6_b_c||tdqs6_b_c\  = M_G_CPU0_SB_DQS_DN<6>
  \dqs6_b_t||tdqs6_b_t\  = M_G_CPU0_SB_DQS_DP<6>
  VSS114  = GND
  DQ14_B  = M_G_CPU0_SB_DQ<14>
  VSS115  = GND
  DQ15_B  = M_G_CPU0_SB_DQ<15>
  VSS116  = GND
  DQ18_B  = M_G_CPU0_SB_DQ<18>
  VSS117  = GND
  DQ19_B  = M_G_CPU0_SB_DQ<19>
  VSS118  = GND
  \dqs7_b_c||tdqs7_b_c\  = M_G_CPU0_SB_DQS_DN<7>
  \dqs7_b_t||tdqs7_b_t\  = M_G_CPU0_SB_DQS_DP<7>
  VSS119  = GND
  DQ22_B  = M_G_CPU0_SB_DQ<22>
  VSS120  = GND
  DQ23_B  = M_G_CPU0_SB_DQ<23>
  VSS121  = GND
  DQ26_B  = M_G_CPU0_SB_DQ<26>
  VSS122  = GND
  DQ27_B  = M_G_CPU0_SB_DQ<27>
  VSS123  = GND
  \dqs8_b_c||tdqs8_b_c\  = M_G_CPU0_SB_DQS_DN<8>
  \dqs8_b_t||tdqs8_b_t\  = M_G_CPU0_SB_DQS_DP<8>
  VSS124  = GND
  DQ30_B  = M_G_CPU0_SB_DQ<30>
  VSS125  = GND
  DQ31_B  = M_G_CPU0_SB_DQ<31>
  VSS126  = GND
  G1  = GND
  G2  = GND
  G3  = GND

(kicad_pcb
	(version 20260206)
	(generator "pcbnew")
	(generator_version "10.0")
	(general
		(thickness 1.6)
		(legacy_teardrops no)
	)
	(paper "A4")
	(title_block
		(title "03242023_DA0F0TMBIJ0_F0T_Motherboard_J_brd_V01_OCP.brd")
		(comment 1 "Grand Teton / footprint 3833 of 6105 (J14), pads 46-91 of 291")
	)
	(layers
		(0 "F.Cu" signal "TOP")
		(4 "In1.Cu" signal "GND")
		(6 "In2.Cu" signal "IN1")
		(8 "In3.Cu" signal "GND1")
		(10 "In4.Cu" signal "IN2")
		(12 "In5.Cu" signal "GND2")
		(14 "In6.Cu" signal "IN3")
		(16 "In7.Cu" signal "GND3")
		(18 "In8.Cu" signal "VCC")
		(20 "In9.Cu" signal "VCC1")
		(22 "In10.Cu" signal "GND4")
		(24 "In11.Cu" signal "IN4")
		(26 "In12.Cu" signal "GND5")
		(28 "In13.Cu" signal "IN5")
		(30 "In14.Cu" signal "GND6")
		(32 "In15.Cu" signal "IN6")
		(34 "In16.Cu" signal "GND7")
		(2 "B.Cu" signal "BOTTOM")
		(9 "F.Adhes" user "F.Adhesive")
		(11 "B.Adhes" user "B.Adhesive")
		(13 "F.Paste" user "Package Geometry/Pastemask Top")
		(15 "B.Paste" user "Package Geometry/Pastemask Bottom")
		(5 "F.SilkS" user "Ref Des/Silkscreen Top")
		(7 "B.SilkS" user "Ref Des/Silkscreen Bottom")
		(1 "F.Mask" user "Board Geometry/Soldermask Top")
		(3 "B.Mask" user "Board Geometry/Soldermask Bottom")
		(17 "Dwgs.User" user "User.Drawings")
		(19 "Cmts.User" user "User.Comments")
		(21 "Eco1.User" user "User.Eco1")
		(23 "Eco2.User" user "User.Eco2")
		(25 "Edge.Cuts" user "Board Geometry/Outline")
		(27 "Margin" user)
		(31 "F.CrtYd" user "Package Geometry/Place Bound Top")
		(29 "B.CrtYd" user "Package Geometry/Place Bound Bottom")
		(35 "F.Fab" user "Ref Des/Assembly Top")
		(33 "B.Fab" user "Ref Des/Assembly Bottom")
	)
	(footprint ""
		(layer "F.Cu")
		(at 438.978548 -258.091686)
		(property "Reference" "J14"
			(at -3.683 -81.702148 0)
			(unlocked yes)
			(layer "F.SilkS")
			(effects
				(font
					(size 0.7874 0.5842)
					(thickness 0.1524)
				)
				(justify left)
			)
		)
		(property "Value" ""
			(at 0 0 0)
			(layer "F.Fab")
			(effects
				(font
					(size 1.27 1.27)
				)
			)
		)
		(duplicate_pad_numbers_are_jumpers no)
		(pad "46" smd rect
			(at -2.050034 -25.07488 270)
			(size 0.519938 1.4986)
			(layers "F.Cu" "F.Mask" "F.Paste")
			(net "GND")
		)
		(pad "47" smd rect
			(at -2.050034 -24.224996 270)
			(size 0.519938 1.4986)
			(layers "F.Cu" "F.Mask" "F.Paste")
			(net "M_G_CPU0_SA_DQ<28>")
		)
		(pad "48" smd rect
			(at -2.050034 -23.375112 270)
			(size 0.519938 1.4986)
			(layers "F.Cu" "F.Mask" "F.Paste")
			(net "GND")
		)
		(pad "49" smd rect
			(at -2.050034 -22.524974 270)
			(size 0.519938 1.4986)
			(layers "F.Cu" "F.Mask" "F.Paste")
			(net "M_G_CPU0_SA_DQ<29>")
		)
		(pad "50" smd rect
			(at -2.050034 -21.67509 270)
			(size 0.519938 1.4986)
			(layers "F.Cu" "F.Mask" "F.Paste")
			(net "GND")
		)
		(pad "51" smd rect
			(at -2.050034 -20.824952 270)
			(size 0.519938 1.4986)
			(layers "F.Cu" "F.Mask" "F.Paste")
			(net "M_G_CPU0_SA_CB<0>")
		)
		(pad "52" smd rect
			(at -2.050034 -19.975068 270)
			(size 0.519938 1.4986)
			(layers "F.Cu" "F.Mask" "F.Paste")
			(net "GND")
		)
		(pad "53" smd rect
			(at -2.050034 -19.12493 270)
			(size 0.519938 1.4986)
			(layers "F.Cu" "F.Mask" "F.Paste")
			(net "M_G_CPU0_SA_CB<1>")
		)
		(pad "54" smd rect
			(at -2.050034 -18.275046 270)
			(size 0.519938 1.4986)
			(layers "F.Cu" "F.Mask" "F.Paste")
			(net "GND")
		)
		(pad "55" smd rect
			(at -2.050034 -17.424908 270)
			(size 0.519938 1.4986)
			(layers "F.Cu" "F.Mask" "F.Paste")
			(net "M_G_CPU0_SA_DQS_DP<4>")
		)
		(pad "56" smd rect
			(at -2.050034 -16.575024 270)
			(size 0.519938 1.4986)
			(layers "F.Cu" "F.Mask" "F.Paste")
			(net "M_G_CPU0_SA_DQS_DN<4>")
		)
		(pad "57" smd rect
			(at -2.050034 -15.724886 270)
			(size 0.519938 1.4986)
			(layers "F.Cu" "F.Mask" "F.Paste")
			(net "GND")
		)
		(pad "58" smd rect
			(at -2.050034 -14.875002 270)
			(size 0.519938 1.4986)
			(layers "F.Cu" "F.Mask" "F.Paste")
			(net "M_G_CPU0_SA_CB<4>")
		)
		(pad "59" smd rect
			(at -2.050034 -14.025118 270)
			(size 0.519938 1.4986)
			(layers "F.Cu" "F.Mask" "F.Paste")
			(net "GND")
		)
		(pad "60" smd rect
			(at -2.050034 -13.17498 270)
			(size 0.519938 1.4986)
			(layers "F.Cu" "F.Mask" "F.Paste")
			(net "M_G_CPU0_SA_CB<5>")
		)
		(pad "61" smd rect
			(at -2.050034 -12.325096 270)
			(size 0.519938 1.4986)
			(layers "F.Cu" "F.Mask" "F.Paste")
			(net "GND")
		)
		(pad "62" smd rect
			(at -2.050034 -11.474958 270)
			(size 0.519938 1.4986)
			(layers "F.Cu" "F.Mask" "F.Paste")
			(net "M_G_CPU0_ALERT_N")
		)
		(pad "63" smd rect
			(at -2.050034 -10.625074 270)
			(size 0.519938 1.4986)
			(layers "F.Cu" "F.Mask" "F.Paste")
			(net "GND")
		)
		(pad "64" smd rect
			(at -2.050034 -9.774936 270)
			(size 0.519938 1.4986)
			(layers "F.Cu" "F.Mask" "F.Paste")
			(net "M_G_CPU0_SA_CS_N<2>")
		)
		(pad "65" smd rect
			(at -2.050034 -8.925052 270)
			(size 0.519938 1.4986)
			(layers "F.Cu" "F.Mask" "F.Paste")
			(net "GND")
		)
		(pad "66" smd rect
			(at -2.050034 -8.074914 270)
			(size 0.519938 1.4986)
			(layers "F.Cu" "F.Mask" "F.Paste")
			(net "M_G_CPU0_SA_CA<0>")
		)
		(pad "67" smd rect
			(at -2.050034 -7.22503 270)
			(size 0.519938 1.4986)
			(layers "F.Cu" "F.Mask" "F.Paste")
			(net "GND")
		)
		(pad "68" smd rect
			(at -2.050034 -6.374892 270)
			(size 0.519938 1.4986)
			(layers "F.Cu" "F.Mask" "F.Paste")
			(net "M_G_CPU0_SA_CA<2>")
		)
		(pad "69" smd rect
			(at -2.050034 -5.525008 270)
			(size 0.519938 1.4986)
			(layers "F.Cu" "F.Mask" "F.Paste")
			(net "GND")
		)
		(pad "70" smd rect
			(at -2.050034 -4.675124 270)
			(size 0.519938 1.4986)
			(layers "F.Cu" "F.Mask" "F.Paste")
			(net "M_G_CPU0_SA_CA<4>")
		)
		(pad "71" smd rect
			(at -2.050034 -3.824986 270)
			(size 0.519938 1.4986)
			(layers "F.Cu" "F.Mask" "F.Paste")
			(net "GND")
		)
		(pad "72" smd rect
			(at -2.050034 -2.975102 270)
			(size 0.519938 1.4986)
			(layers "F.Cu" "F.Mask" "F.Paste")
			(net "M_G_CPU0_SA_CA<6>")
		)
		(pad "73" smd rect
			(at -2.050034 -2.124964 270)
			(size 0.519938 1.4986)
			(layers "F.Cu" "F.Mask" "F.Paste")
			(net "GND")
		)
		(pad "74" smd rect
			(at -2.050034 -1.27508 270)
			(size 0.519938 1.4986)
			(layers "F.Cu" "F.Mask" "F.Paste")
			(net "M_G_CPU0_SA_PAR")
		)
		(pad "75" smd rect
			(at -2.050034 -0.424942 270)
			(size 0.519938 1.4986)
			(layers "F.Cu" "F.Mask" "F.Paste")
			(net "GND")
		)
		(pad "76" smd rect
			(at -2.050034 5.525008 270)
			(size 0.519938 1.4986)
			(layers "F.Cu" "F.Mask" "F.Paste")
			(net "M_G_CPU0_SB_CA<0>")
		)
		(pad "77" smd rect
			(at -2.050034 6.374892 270)
			(size 0.519938 1.4986)
			(layers "F.Cu" "F.Mask" "F.Paste")
			(net "GND")
		)
		(pad "78" smd rect
			(at -2.050034 7.22503 270)
			(size 0.519938 1.4986)
			(layers "F.Cu" "F.Mask" "F.Paste")
			(net "M_G_CPU0_SB_CA<2>")
		)
		(pad "79" smd rect
			(at -2.050034 8.074914 270)
			(size 0.519938 1.4986)
			(layers "F.Cu" "F.Mask" "F.Paste")
			(net "GND")
		)
		(pad "80" smd rect
			(at -2.050034 8.925052 270)
			(size 0.519938 1.4986)
			(layers "F.Cu" "F.Mask" "F.Paste")
			(net "M_G_CPU0_SB_CA<4>")
		)
		(pad "81" smd rect
			(at -2.050034 9.774936 270)
			(size 0.519938 1.4986)
			(layers "F.Cu" "F.Mask" "F.Paste")
			(net "GND")
		)
		(pad "82" smd rect
			(at -2.050034 10.625074 270)
			(size 0.519938 1.4986)
			(layers "F.Cu" "F.Mask" "F.Paste")
			(net "M_G_CPU0_SB_CA<6>")
		)
		(pad "83" smd rect
			(at -2.050034 11.474958 270)
			(size 0.519938 1.4986)
			(layers "F.Cu" "F.Mask" "F.Paste")
			(net "GND")
		)
		(pad "84" smd rect
			(at -2.050034 12.325096 270)
			(size 0.519938 1.4986)
			(layers "F.Cu" "F.Mask" "F.Paste")
			(net "M_G_CPU0_SB_CS_N<2>")
		)
		(pad "85" smd rect
			(at -2.050034 13.17498 270)
			(size 0.519938 1.4986)
			(layers "F.Cu" "F.Mask" "F.Paste")
			(net "GND")
		)
		(pad "86" smd rect
			(at -2.050034 14.025118 270)
			(size 0.519938 1.4986)
			(layers "F.Cu" "F.Mask" "F.Paste")
			(net "M_G_CPU0_SA_RSP<1>")
		)
		(pad "87" smd rect
			(at -2.050034 14.875002 270)
			(size 0.519938 1.4986)
			(layers "F.Cu" "F.Mask" "F.Paste")
			(net "M_G_CPU0_SB_RSP<1>")
		)
		(pad "88" smd rect
			(at -2.050034 15.724886 270)
			(size 0.519938 1.4986)
			(layers "F.Cu" "F.Mask" "F.Paste")
			(net "GND")
		)
		(pad "89" smd rect
			(at -2.050034 16.575024 270)
			(size 0.519938 1.4986)
			(layers "F.Cu" "F.Mask" "F.Paste")
			(net "M_G_CPU0_SB_CB<4>")
		)
		(pad "90" smd rect
			(at -2.050034 17.424908 270)
			(size 0.519938 1.4986)
			(layers "F.Cu" "F.Mask" "F.Paste")
			(net "GND")
		)
		(pad "91" smd rect
			(at -2.050034 18.275046 270)
			(size 0.519938 1.4986)
			(layers "F.Cu" "F.Mask" "F.Paste")
			(net "M_G_CPU0_SB_CB<5>")
		)
	)
)
